(kicad_pcb
	(version 20241229)
	(generator "pcbnew")
	(generator_version "9.0")
	(general
		(thickness 1.711)
		(legacy_teardrops no)
	)
	(paper "A4")
	(title_block
		(title "Antmicro Baseboard for Jetson AGX Thor")
		(date "2026-02-18")
		(rev "1.1.0")
		(company "Antmicro Ltd")
		(comment 1 "www.antmicro.com")
		(comment 9 "footprints 191-195 of 1170")
	)
	(layers
		(0 "F.Cu" signal)
		(4 "In1.Cu" signal)
		(6 "In2.Cu" signal)
		(8 "In3.Cu" signal)
		(10 "In4.Cu" jumper)
		(12 "In5.Cu" signal)
		(14 "In6.Cu" signal)
		(16 "In7.Cu" signal)
		(18 "In8.Cu" signal)
		(2 "B.Cu" signal)
		(9 "F.Adhes" user "F.Adhesive")
		(11 "B.Adhes" user "B.Adhesive")
		(13 "F.Paste" user)
		(15 "B.Paste" user)
		(5 "F.SilkS" user "F.Silkscreen")
		(7 "B.SilkS" user "B.Silkscreen")
		(1 "F.Mask" user)
		(3 "B.Mask" user)
		(17 "Dwgs.User" user "User.Drawings")
		(19 "Cmts.User" user "User.Comments")
		(21 "Eco1.User" user "User.Eco1")
		(23 "Eco2.User" user "User.Eco2")
		(25 "Edge.Cuts" user)
		(27 "Margin" user)
		(31 "F.CrtYd" user "F.Courtyard")
		(29 "B.CrtYd" user "B.Courtyard")
		(35 "F.Fab" user)
		(33 "B.Fab" user)
	)
	(footprint "antmicro-footprints:R_0402_1005Metric"
		(layer "F.Cu")
		(at 196.6 73.5 -90)
		(descr "Resistor SMD 0402")
		(tags "resistor SMD 0402")
		(property "Reference" "R225"
			(at -3.8 0.4 90)
			(layer "F.SilkS")
			(effects
				(font
					(size 0.7 0.7)
					(thickness 0.15)
				)
				(justify right top)
			)
		)
		(property "Value" "R_4k7_0402"
			(at -1.011843 1.772046 90)
			(layer "F.Fab")
			(effects
				(font
					(size 0.7 0.7)
					(thickness 0.15)
				)
				(justify right top)
			)
		)
		(property "Datasheet" "https://www.bourns.com/docs/product-datasheets/cr.pdf"
			(at 0 0 90)
			(layer "F.Fab")
			(hide yes)
			(effects
				(font
					(size 1.27 1.27)
					(thickness 0.15)
				)
			)
		)
		(property "Description" "SMD Chip Resistor, 4.7 kohm, ± 1%, 62.5 mW, 0402 [1005 Metric], Thick Film, General Purpose"
			(at 0 0 90)
			(layer "F.Fab")
			(hide yes)
			(effects
				(font
					(size 1.27 1.27)
					(thickness 0.15)
				)
			)
		)
		(property "Manufacturer" "Bourns"
			(at 0 0 270)
			(unlocked yes)
			(layer "F.Fab")
			(hide yes)
			(effects
				(font
					(size 1 1)
					(thickness 0.15)
				)
			)
		)
		(property "MPN" "CR0402-FX-4701GLF"
			(at 0 0 270)
			(unlocked yes)
			(layer "F.Fab")
			(hide yes)
			(effects
				(font
					(size 1 1)
					(thickness 0.15)
				)
			)
		)
		(property "Val" "4k7"
			(at 0 0 270)
			(unlocked yes)
			(layer "F.Fab")
			(hide yes)
			(effects
				(font
					(size 1 1)
					(thickness 0.15)
				)
			)
		)
		(property "License" "Apache-2.0"
			(at 0 0 270)
			(unlocked yes)
			(layer "F.Fab")
			(hide yes)
			(effects
				(font
					(size 1 1)
					(thickness 0.15)
				)
			)
		)
		(property "Author" "Antmicro"
			(at 0 0 270)
			(unlocked yes)
			(layer "F.Fab")
			(hide yes)
			(effects
				(font
					(size 1 1)
					(thickness 0.15)
				)
			)
		)
		(property "Tolerance" "1%"
			(at 0 0 270)
			(unlocked yes)
			(layer "F.Fab")
			(hide yes)
			(effects
				(font
					(size 1 1)
					(thickness 0.15)
				)
			)
		)
		(sheetname "/USB Debug, PD/")
		(sheetfile "usb_debug_pd.kicad_sch")
		(attr smd)
		(fp_poly
			(pts
				(xy -0.925 -0.47) (xy 0.925 -0.47) (xy 0.925 0.47) (xy -0.925 0.47)
			)
			(stroke
				(width 0.05)
				(type default)
			)
			(fill no)
			(layer "F.CrtYd")
		)
		(fp_poly
			(pts
				(xy -0.5 -0.25) (xy 0.5 -0.25) (xy 0.5 0.25) (xy -0.5 0.25)
			)
			(stroke
				(width 0.15)
				(type solid)
			)
			(fill no)
			(layer "F.Fab")
		)
		(fp_text user "${REFERENCE}"
			(at -0.95 3.168 90)
			(layer "F.Fab")
			(effects
				(font
					(size 0.7 0.7)
					(thickness 0.15)
				)
				(justify right top)
			)
		)
		(fp_text user "Author: Antmicro"
			(at -0.95 4.169 90)
			(layer "F.Fab")
			(effects
				(font
					(size 0.7 0.7)
					(thickness 0.15)
				)
				(justify right top)
			)
		)
		(fp_text user "License: Apache-2.0"
			(at -0.949999 5.169 90)
			(layer "F.Fab")
			(effects
				(font
					(size 0.7 0.7)
					(thickness 0.15)
				)
				(justify right top)
			)
		)
		(pad "1" smd roundrect
			(at -0.48 0 270)
			(size 0.59 0.64)
			(layers "F.Cu" "F.Mask" "F.Paste")
			(roundrect_rratio 0.25)
			(net 2 "+3V3")
			(pintype "passive")
		)
		(pad "2" smd roundrect
			(at 0.48 0 270)
			(size 0.59 0.64)
			(layers "F.Cu" "F.Mask" "F.Paste")
			(roundrect_rratio 0.25)
			(net 953 "/USB Debug, PD/PDC_I2C1_IRQn")
			(pintype "passive")
		)
	)
	(footprint "antmicro-footprints:C_0805_2012Metric"
		(layer "F.Cu")
		(at 172.555 126.93 90)
		(descr "Capacitor SMD 0805")
		(tags "capacitor SMD 0805")
		(property "Reference" "C273"
			(at 1.53 -4.855 90)
			(layer "F.SilkS")
			(effects
				(font
					(size 0.7 0.7)
					(thickness 0.15)
				)
				(justify left bottom)
			)
		)
		(property "Value" "C_22u_25V_0805"
			(at -2.055717 1.963152 90)
			(layer "F.Fab")
			(effects
				(font
					(size 0.7 0.7)
					(thickness 0.15)
				)
				(justify left bottom)
			)
		)
		(property "Datasheet" "https://product.samsungsem.com/mlcc/CL21A226MAYNNN.do"
			(at 0 0 90)
			(layer "F.Fab")
			(hide yes)
			(effects
				(font
					(size 1.27 1.27)
					(thickness 0.15)
				)
			)
		)
		(property "Description" "SMT Multilayer Ceramic Capacitor, 22uF, +/-20%, 25V, X5R, 0805 [2012 Metric]"
			(at 0 0 90)
			(layer "F.Fab")
			(hide yes)
			(effects
				(font
					(size 1.27 1.27)
					(thickness 0.15)
				)
			)
		)
		(property "MPN" "CL21A226MAYNNNE"
			(at 0 0 90)
			(unlocked yes)
			(layer "F.Fab")
			(hide yes)
			(effects
				(font
					(size 1 1)
					(thickness 0.15)
				)
			)
		)
		(property "Manufacturer" "Samsung Electro-Mechanics"
			(at 0 0 90)
			(unlocked yes)
			(layer "F.Fab")
			(hide yes)
			(effects
				(font
					(size 1 1)
					(thickness 0.15)
				)
			)
		)
		(property "License" "Apache-2.0"
			(at 0 0 90)
			(unlocked yes)
			(layer "F.Fab")
			(hide yes)
			(effects
				(font
					(size 1 1)
					(thickness 0.15)
				)
			)
		)
		(property "Author" "Antmicro"
			(at 0 0 90)
			(unlocked yes)
			(layer "F.Fab")
			(hide yes)
			(effects
				(font
					(size 1 1)
					(thickness 0.15)
				)
			)
		)
		(property "Val" "22u"
			(at 0 0 90)
			(unlocked yes)
			(layer "F.Fab")
			(hide yes)
			(effects
				(font
					(size 1 1)
					(thickness 0.15)
				)
			)
		)
		(property "Voltage" "25V"
			(at 0 0 90)
			(unlocked yes)
			(layer "F.Fab")
			(hide yes)
			(effects
				(font
					(size 1 1)
					(thickness 0.15)
				)
			)
		)
		(property "Dielectric" "X5R"
			(at 0 0 90)
			(unlocked yes)
			(layer "F.Fab")
			(hide yes)
			(effects
				(font
					(size 1 1)
					(thickness 0.15)
				)
			)
		)
		(property "Public" "False"
			(at 0 0 90)
			(unlocked yes)
			(layer "F.Fab")
			(hide yes)
			(effects
				(font
					(size 1 1)
					(thickness 0.15)
				)
			)
		)
		(sheetname "/DCDC/")
		(sheetfile "dcdc.kicad_sch")
		(attr smd)
		(fp_line
			(start -0.3 -0.7)
			(end 0.3 -0.7)
			(stroke
				(width 0.15)
				(type solid)
			)
			(layer "F.SilkS")
		)
		(fp_line
			(start -0.3 0.7)
			(end 0.3 0.7)
			(stroke
				(width 0.15)
				(type solid)
			)
			(layer "F.SilkS")
		)
		(fp_rect
			(start 1.95 -0.9)
			(end -1.95 0.9)
			(stroke
				(width 0.05)
				(type default)
			)
			(fill no)
			(layer "F.CrtYd")
		)
		(fp_rect
			(start -0.95 -0.675)
			(end 0.95 0.675)
			(stroke
				(width 0.15)
				(type solid)
			)
			(fill no)
			(layer "F.Fab")
		)
		(fp_text user "Author: Antmicro"
			(at -1.9 5.947 90)
			(layer "F.Fab")
			(effects
				(font
					(size 0.7 0.7)
					(thickness 0.15)
				)
				(justify left bottom)
			)
		)
		(fp_text user "License: Apache-2.0"
			(at -1.9 4.947 90)
			(layer "F.Fab")
			(effects
				(font
					(size 0.7 0.7)
					(thickness 0.15)
				)
				(justify left bottom)
			)
		)
		(fp_text user "${REFERENCE}"
			(at -1.9 3.947 90)
			(layer "F.Fab")
			(effects
				(font
					(size 0.7 0.7)
					(thickness 0.15)
				)
				(justify left bottom)
			)
		)
		(pad "1" smd roundrect
			(at -1.1 0 90)
			(size 1.2 1.3)
			(layers "F.Cu" "F.Mask" "F.Paste")
			(roundrect_rratio 0.25)
			(net 1 "GND")
			(pintype "passive")
		)
		(pad "2" smd roundrect
			(at 1.1 0 90)
			(size 1.2 1.3)
			(layers "F.Cu" "F.Mask" "F.Paste")
			(roundrect_rratio 0.25)
			(net 13 "VCC")
			(pintype "passive")
		)
	)
	(footprint "antmicro-footprints:C_0402_1005Metric"
		(layer "F.Cu")
		(at 127.819999 64.87 180)
		(descr "Capacitor SMD 0402")
		(tags "capacitor SMD 0402")
		(property "Reference" "C375"
			(at -1.860001 -0.52 0)
			(layer "F.SilkS")
			(effects
				(font
					(size 0.7 0.7)
					(thickness 0.15)
				)
				(justify right top)
			)
		)
		(property "Value" "C_1u_0402"
			(at -1.022927 2.155213 0)
			(layer "F.Fab")
			(effects
				(font
					(size 0.7 0.7)
					(thickness 0.15)
				)
				(justify right top)
			)
		)
		(property "Datasheet" "https://product.tdk.com/en/search/capacitor/ceramic/mlcc/info?part_no=C1005X6S1A105K050BC"
			(at 0 0 0)
			(layer "F.Fab")
			(hide yes)
			(effects
				(font
					(size 1.27 1.27)
					(thickness 0.15)
				)
			)
		)
		(property "Description" "SMD Multilayer Ceramic Capacitor, 1 µF, 10 V, 0402 [1005 Metric], ± 10%, X6S, C"
			(at 0 0 0)
			(layer "F.Fab")
			(hide yes)
			(effects
				(font
					(size 1.27 1.27)
					(thickness 0.15)
				)
			)
		)
		(property "Manufacturer" "TDK"
			(at 0 0 180)
			(unlocked yes)
			(layer "F.Fab")
			(hide yes)
			(effects
				(font
					(size 1 1)
					(thickness 0.15)
				)
			)
		)
		(property "MPN" "C1005X6S1A105K050BC"
			(at 0 0 180)
			(unlocked yes)
			(layer "F.Fab")
			(hide yes)
			(effects
				(font
					(size 1 1)
					(thickness 0.15)
				)
			)
		)
		(property "Val" "1u"
			(at 0 0 180)
			(unlocked yes)
			(layer "F.Fab")
			(hide yes)
			(effects
				(font
					(size 1 1)
					(thickness 0.15)
				)
			)
		)
		(property "License" "Apache-2.0"
			(at 0 0 180)
			(unlocked yes)
			(layer "F.Fab")
			(hide yes)
			(effects
				(font
					(size 1 1)
					(thickness 0.15)
				)
			)
		)
		(property "Author" "Antmicro"
			(at 0 0 180)
			(unlocked yes)
			(layer "F.Fab")
			(hide yes)
			(effects
				(font
					(size 1 1)
					(thickness 0.15)
				)
			)
		)
		(property "Voltage" ""
			(at 0 0 180)
			(unlocked yes)
			(layer "F.Fab")
			(hide yes)
			(effects
				(font
					(size 1 1)
					(thickness 0.15)
				)
			)
		)
		(property "Dielectric" ""
			(at 0 0 180)
			(unlocked yes)
			(layer "F.Fab")
			(hide yes)
			(effects
				(font
					(size 1 1)
					(thickness 0.15)
				)
			)
		)
		(sheetname "/DCDC/")
		(sheetfile "dcdc.kicad_sch")
		(attr smd)
		(fp_poly
			(pts
				(xy -0.925 -0.47) (xy -0.925 0.47) (xy 0.925 0.47) (xy 0.925 -0.47)
			)
			(stroke
				(width 0.05)
				(type default)
			)
			(fill no)
			(layer "F.CrtYd")
		)
		(fp_line
			(start 0.504 0.248)
			(end -0.494 0.248)
			(stroke
				(width 0.15)
				(type solid)
			)
			(layer "F.Fab")
		)
		(fp_line
			(start 0.504 -0.25)
			(end 0.504 0.248)
			(stroke
				(width 0.15)
				(type solid)
			)
			(layer "F.Fab")
		)
		(fp_line
			(start -0.494 0.248)
			(end -0.494 -0.25)
			(stroke
				(width 0.15)
				(type solid)
			)
			(layer "F.Fab")
		)
		(fp_line
			(start -0.494 -0.25)
			(end 0.504 -0.25)
			(stroke
				(width 0.15)
				(type solid)
			)
			(layer "F.Fab")
		)
		(fp_text user "License: Apache-2.0"
			(at -0.939 5.799 0)
			(layer "F.Fab")
			(effects
				(font
					(size 0.7 0.7)
					(thickness 0.15)
				)
				(justify right top)
			)
		)
		(fp_text user "${REFERENCE}"
			(at -0.939 4.599 0)
			(layer "F.Fab")
			(effects
				(font
					(size 0.7 0.7)
					(thickness 0.15)
				)
				(justify right top)
			)
		)
		(fp_text user "Author: Antmicro"
			(at -0.939 3.399 0)
			(layer "F.Fab")
			(effects
				(font
					(size 0.7 0.7)
					(thickness 0.15)
				)
				(justify right top)
			)
		)
		(pad "1" smd roundrect
			(at -0.48 0 180)
			(size 0.59 0.64)
			(layers "F.Cu" "F.Mask" "F.Paste")
			(roundrect_rratio 0.25)
			(net 1 "GND")
			(pintype "passive")
		)
		(pad "2" smd roundrect
			(at 0.48 0 180)
			(size 0.59 0.64)
			(layers "F.Cu" "F.Mask" "F.Paste")
			(roundrect_rratio 0.25)
			(net 1274 "/DCDC/5V_{AON}_VDD")
			(pintype "passive")
		)
	)
	(footprint "antmicro-footprints:C_0805_2012Metric"
		(layer "F.Cu")
		(at 174.99 93.32 -90)
		(descr "Capacitor SMD 0805")
		(tags "capacitor SMD 0805")
		(property "Reference" "C286"
			(at 1.745 0.425 90)
			(layer "F.SilkS")
			(effects
				(font
					(size 0.7 0.7)
					(thickness 0.15)
				)
				(justify right top)
			)
		)
		(property "Value" "C_22u_25V_0805"
			(at -2.055717 1.963152 90)
			(layer "F.Fab")
			(effects
				(font
					(size 0.7 0.7)
					(thickness 0.15)
				)
				(justify right top)
			)
		)
		(property "Datasheet" "https://product.samsungsem.com/mlcc/CL21A226MAYNNN.do"
			(at 0 0 90)
			(layer "F.Fab")
			(hide yes)
			(effects
				(font
					(size 1.27 1.27)
					(thickness 0.15)
				)
			)
		)
		(property "Description" "SMT Multilayer Ceramic Capacitor, 22uF, +/-20%, 25V, X5R, 0805 [2012 Metric]"
			(at 0 0 90)
			(layer "F.Fab")
			(hide yes)
			(effects
				(font
					(size 1.27 1.27)
					(thickness 0.15)
				)
			)
		)
		(property "MPN" "CL21A226MAYNNNE"
			(at 0 0 270)
			(unlocked yes)
			(layer "F.Fab")
			(hide yes)
			(effects
				(font
					(size 1 1)
					(thickness 0.15)
				)
			)
		)
		(property "Manufacturer" "Samsung Electro-Mechanics"
			(at 0 0 270)
			(unlocked yes)
			(layer "F.Fab")
			(hide yes)
			(effects
				(font
					(size 1 1)
					(thickness 0.15)
				)
			)
		)
		(property "License" "Apache-2.0"
			(at 0 0 270)
			(unlocked yes)
			(layer "F.Fab")
			(hide yes)
			(effects
				(font
					(size 1 1)
					(thickness 0.15)
				)
			)
		)
		(property "Author" "Antmicro"
			(at 0 0 270)
			(unlocked yes)
			(layer "F.Fab")
			(hide yes)
			(effects
				(font
					(size 1 1)
					(thickness 0.15)
				)
			)
		)
		(property "Val" "22u"
			(at 0 0 270)
			(unlocked yes)
			(layer "F.Fab")
			(hide yes)
			(effects
				(font
					(size 1 1)
					(thickness 0.15)
				)
			)
		)
		(property "Voltage" "25V"
			(at 0 0 270)
			(unlocked yes)
			(layer "F.Fab")
			(hide yes)
			(effects
				(font
					(size 1 1)
					(thickness 0.15)
				)
			)
		)
		(property "Dielectric" "X5R"
			(at 0 0 270)
			(unlocked yes)
			(layer "F.Fab")
			(hide yes)
			(effects
				(font
					(size 1 1)
					(thickness 0.15)
				)
			)
		)
		(property "Public" "False"
			(at 0 0 270)
			(unlocked yes)
			(layer "F.Fab")
			(hide yes)
			(effects
				(font
					(size 1 1)
					(thickness 0.15)
				)
			)
		)
		(component_classes
			(class "DCDC_SOM")
		)
		(sheetname "/DCDC/")
		(sheetfile "dcdc.kicad_sch")
		(attr smd)
		(fp_line
			(start -0.3 0.7)
			(end 0.3 0.7)
			(stroke
				(width 0.15)
				(type solid)
			)
			(layer "F.SilkS")
		)
		(fp_line
			(start -0.3 -0.7)
			(end 0.3 -0.7)
			(stroke
				(width 0.15)
				(type solid)
			)
			(layer "F.SilkS")
		)
		(fp_rect
			(start 1.95 -0.9)
			(end -1.95 0.9)
			(stroke
				(width 0.05)
				(type default)
			)
			(fill no)
			(layer "F.CrtYd")
		)
		(fp_rect
			(start -0.95 -0.675)
			(end 0.95 0.675)
			(stroke
				(width 0.15)
				(type solid)
			)
			(fill no)
			(layer "F.Fab")
		)
		(fp_text user "Author: Antmicro"
			(at -1.9 5.947 90)
			(layer "F.Fab")
			(effects
				(font
					(size 0.7 0.7)
					(thickness 0.15)
				)
				(justify right top)
			)
		)
		(fp_text user "License: Apache-2.0"
			(at -1.9 4.947 90)
			(layer "F.Fab")
			(effects
				(font
					(size 0.7 0.7)
					(thickness 0.15)
				)
				(justify right top)
			)
		)
		(fp_text user "${REFERENCE}"
			(at -1.9 3.947 90)
			(layer "F.Fab")
			(effects
				(font
					(size 0.7 0.7)
					(thickness 0.15)
				)
				(justify right top)
			)
		)
		(pad "1" smd roundrect
			(at -1.1 0 270)
			(size 1.2 1.3)
			(layers "F.Cu" "F.Mask" "F.Paste")
			(roundrect_rratio 0.25)
			(net 1 "GND")
			(pintype "passive")
		)
		(pad "2" smd roundrect
			(at 1.1 0 270)
			(size 1.2 1.3)
			(layers "F.Cu" "F.Mask" "F.Paste")
			(roundrect_rratio 0.25)
			(net 903 "/DCDC/16V_OUT")
			(pintype "passive")
		)
	)
	(footprint "antmicro-footprints:C_0402_1005Metric"
		(layer "F.Cu")
		(at 182.764468 91.565 -90)
		(descr "Capacitor SMD 0402")
		(tags "capacitor SMD 0402")
		(property "Reference" "C245"
			(at -0.91 -0.5 90)
			(layer "F.SilkS")
			(effects
				(font
					(size 0.7 0.7)
					(thickness 0.15)
				)
				(justify right top)
			)
		)
		(property "Value" "C_4u7_25V_0402"
			(at -1.022927 2.155213 90)
			(layer "F.Fab")
			(effects
				(font
					(size 0.7 0.7)
					(thickness 0.15)
				)
				(justify right top)
			)
		)
		(property "Datasheet" "https://www.murata.com/products/productdetail?partno=GRM155C61E475ME15%23"
			(at 0 0 90)
			(layer "F.Fab")
			(hide yes)
			(effects
				(font
					(size 1.27 1.27)
					(thickness 0.15)
				)
			)
		)
		(property "Description" "SMD Multilayer Ceramic Capacitor"
			(at 0 0 90)
			(layer "F.Fab")
			(hide yes)
			(effects
				(font
					(size 1.27 1.27)
					(thickness 0.15)
				)
			)
		)
		(property "MPN" "GRM155C61E475ME15J"
			(at 0 0 270)
			(unlocked yes)
			(layer "F.Fab")
			(hide yes)
			(effects
				(font
					(size 1 1)
					(thickness 0.15)
				)
			)
		)
		(property "Manufacturer" "Murata"
			(at 0 0 270)
			(unlocked yes)
			(layer "F.Fab")
			(hide yes)
			(effects
				(font
					(size 1 1)
					(thickness 0.15)
				)
			)
		)
		(property "License" "Apache-2.0"
			(at 0 0 270)
			(unlocked yes)
			(layer "F.Fab")
			(hide yes)
			(effects
				(font
					(size 1 1)
					(thickness 0.15)
				)
			)
		)
		(property "Author" "Antmicro"
			(at 0 0 270)
			(unlocked yes)
			(layer "F.Fab")
			(hide yes)
			(effects
				(font
					(size 1 1)
					(thickness 0.15)
				)
			)
		)
		(property "Val" "4u7"
			(at 0 0 270)
			(unlocked yes)
			(layer "F.Fab")
			(hide yes)
			(effects
				(font
					(size 1 1)
					(thickness 0.15)
				)
			)
		)
		(property "Voltage" "25V"
			(at 0 0 270)
			(unlocked yes)
			(layer "F.Fab")
			(hide yes)
			(effects
				(font
					(size 1 1)
					(thickness 0.15)
				)
			)
		)
		(property "Dielectric" "X5S"
			(at 0 0 270)
			(unlocked yes)
			(layer "F.Fab")
			(hide yes)
			(effects
				(font
					(size 1 1)
					(thickness 0.15)
				)
			)
		)
		(component_classes
			(class "DCDC_SOM")
		)
		(sheetname "/DCDC/")
		(sheetfile "dcdc.kicad_sch")
		(attr smd)
		(fp_rect
			(start -0.925 -0.47)
			(end 0.925 0.47)
			(stroke
				(width 0.05)
				(type default)
			)
			(fill no)
			(layer "F.CrtYd")
		)
		(fp_line
			(start -0.494 0.248)
			(end -0.494 -0.25)
			(stroke
				(width 0.15)
				(type solid)
			)
			(layer "F.Fab")
		)
		(fp_line
			(start 0.504 0.248)
			(end -0.494 0.248)
			(stroke
				(width 0.15)
				(type solid)
			)
			(layer "F.Fab")
		)
		(fp_line
			(start -0.494 -0.25)
			(end 0.504 -0.25)
			(stroke
				(width 0.15)
				(type solid)
			)
			(layer "F.Fab")
		)
		(fp_line
			(start 0.504 -0.25)
			(end 0.504 0.248)
			(stroke
				(width 0.15)
				(type solid)
			)
			(layer "F.Fab")
		)
		(fp_text user "${REFERENCE}"
			(at -0.939 4.599 90)
			(layer "F.Fab")
			(effects
				(font
					(size 0.7 0.7)
					(thickness 0.15)
				)
				(justify right top)
			)
		)
		(fp_text user "Author: Antmicro"
			(at -0.939 3.399 90)
			(layer "F.Fab")
			(effects
				(font
					(size 0.7 0.7)
					(thickness 0.15)
				)
				(justify right top)
			)
		)
		(fp_text user "License: Apache-2.0"
			(at -0.939 5.799 90)
			(layer "F.Fab")
			(effects
				(font
					(size 0.7 0.7)
					(thickness 0.15)
				)
				(justify right top)
			)
		)
		(pad "1" smd roundrect
			(at -0.48 0 270)
			(size 0.59 0.64)
			(layers "F.Cu" "F.Mask" "F.Paste")
			(roundrect_rratio 0.25)
			(net 1 "GND")
			(pintype "passive")
		)
		(pad "2" smd roundrect
			(at 0.48 0 270)
			(size 0.59 0.64)
			(layers "F.Cu" "F.Mask" "F.Paste")
			(roundrect_rratio 0.25)
			(net 900 "/DCDC/16V_VDRV")
			(pintype "passive")
		)
	)
)
